# T6G (Grand Teton) — schematic netlist excerpt (pin names and nets, part order shuffled) for the footprints in the layout excerpt that follows; sources: Cadence DE-HDL packaged netlist, KiCad conversion of 04192023_DAF0TMB3IC0_F0TG_MB_C_brd_V02_OCP.brd

R598  Q_RES  0 5% CHIP  pkg 0201LF  page 331 : A = CLK_100M_RETIMER_CPU1_P1_R_DN ; B = CLK_100M_RETIMER_CPU1_P1_DN
R1318  Q_RES  4.7K 5% CHIP  pkg 0402LF  page 171 : A = PD_U212_EN_N ; B = GND
PR314  Q_RES  0 5% CHIP  pkg 0402LF  page 193 : A = P12V_AUX ; B = PVDDCR_CPU0_P0_VINSEN

(kicad_pcb
	(version 20260206)
	(generator "pcbnew")
	(generator_version "10.0")
	(general
		(thickness 1.6)
		(legacy_teardrops no)
	)
	(paper "A4")
	(title_block
		(title "04192023_DAF0TMB3IC0_F0TG_MB_C_brd_V02_OCP.brd")
		(comment 1 "Grand Teton / footprints 2836-2838 of 8354")
	)
	(layers
		(0 "F.Cu" signal "TOP")
		(4 "In1.Cu" signal "GND")
		(6 "In2.Cu" signal "IN1")
		(8 "In3.Cu" signal "GND1")
		(10 "In4.Cu" signal "IN2")
		(12 "In5.Cu" signal "GND2")
		(14 "In6.Cu" signal "IN3")
		(16 "In7.Cu" signal "GND3")
		(18 "In8.Cu" signal "VCC")
		(20 "In9.Cu" signal "VCC1")
		(22 "In10.Cu" signal "GND4")
		(24 "In11.Cu" signal "IN4")
		(26 "In12.Cu" signal "GND5")
		(28 "In13.Cu" signal "IN5")
		(30 "In14.Cu" signal "GND6")
		(32 "In15.Cu" signal "IN6")
		(34 "In16.Cu" signal "GND7")
		(2 "B.Cu" signal "BOTTOM")
		(9 "F.Adhes" user "F.Adhesive")
		(11 "B.Adhes" user "B.Adhesive")
		(13 "F.Paste" user "Package Geometry/Pastemask Top")
		(15 "B.Paste" user "Package Geometry/Pastemask Bottom")
		(5 "F.SilkS" user "Ref Des/Silkscreen Top")
		(7 "B.SilkS" user "Ref Des/Silkscreen Bottom")
		(1 "F.Mask" user "Board Geometry/Soldermask Top")
		(3 "B.Mask" user "Board Geometry/Soldermask Bottom")
		(17 "Dwgs.User" user "User.Drawings")
		(19 "Cmts.User" user "User.Comments")
		(21 "Eco1.User" user "User.Eco1")
		(23 "Eco2.User" user "User.Eco2")
		(25 "Edge.Cuts" user "Board Geometry/Outline")
		(27 "Margin" user)
		(31 "F.CrtYd" user "Package Geometry/Place Bound Top")
		(29 "B.CrtYd" user "Package Geometry/Place Bound Bottom")
		(35 "F.Fab" user "Ref Des/Assembly Top")
		(33 "B.Fab" user "Ref Des/Assembly Bottom")
	)
	(footprint ""
		(layer "F.Cu")
		(at 384.113278 -139.186158 180)
		(property "Reference" "PR314"
			(at 0 0 180)
			(layer "F.SilkS")
			(hide yes)
			(effects
				(font
					(size 1.27 1.27)
				)
			)
		)
		(property "Value" ""
			(at 0 0 180)
			(layer "F.Fab")
			(effects
				(font
					(size 1.27 1.27)
				)
			)
		)
		(duplicate_pad_numbers_are_jumpers no)
		(fp_line
			(start 0.7874 0.4064)
			(end -0.7874 0.4064)
			(stroke
				(width 0.1524)
				(type default)
			)
			(layer "F.SilkS")
		)
		(fp_line
			(start 0.7874 -0.4064)
			(end 0.7874 0.4064)
			(stroke
				(width 0.1524)
				(type default)
			)
			(layer "F.SilkS")
		)
		(fp_line
			(start -0.7874 0.4064)
			(end -0.7874 -0.4064)
			(stroke
				(width 0.1524)
				(type default)
			)
			(layer "F.SilkS")
		)
		(fp_line
			(start -0.7874 -0.4064)
			(end 0.7874 -0.4064)
			(stroke
				(width 0.1524)
				(type default)
			)
			(layer "F.SilkS")
		)
		(fp_line
			(start 0.67945 0.3048)
			(end 0.120396 0.3048)
			(stroke
				(width 0.1)
				(type default)
			)
			(layer "F.Fab")
		)
		(fp_line
			(start 0.67945 -0.3048)
			(end 0.67945 0.3048)
			(stroke
				(width 0.1)
				(type default)
			)
			(layer "F.Fab")
		)
		(fp_line
			(start 0.12065 -0.2794)
			(end 0.12065 -0.3048)
			(stroke
				(width 0.1)
				(type default)
			)
			(layer "F.Fab")
		)
		(fp_line
			(start 0.12065 -0.3048)
			(end 0.67945 -0.3048)
			(stroke
				(width 0.1)
				(type default)
			)
			(layer "F.Fab")
		)
		(fp_line
			(start 0.120396 0.3048)
			(end 0.120396 0.2794)
			(stroke
				(width 0.1)
				(type default)
			)
			(layer "F.Fab")
		)
		(fp_line
			(start 0.120396 0.2794)
			(end -0.12065 0.2794)
			(stroke
				(width 0.1)
				(type default)
			)
			(layer "F.Fab")
		)
		(fp_line
			(start -0.12065 0.3048)
			(end -0.67945 0.3048)
			(stroke
				(width 0.1)
				(type default)
			)
			(layer "F.Fab")
		)
		(fp_line
			(start -0.12065 0.2794)
			(end -0.12065 0.3048)
			(stroke
				(width 0.1)
				(type default)
			)
			(layer "F.Fab")
		)
		(fp_line
			(start -0.12065 -0.2794)
			(end 0.12065 -0.2794)
			(stroke
				(width 0.1)
				(type default)
			)
			(layer "F.Fab")
		)
		(fp_line
			(start -0.12065 -0.305054)
			(end -0.12065 -0.2794)
			(stroke
				(width 0.1)
				(type default)
			)
			(layer "F.Fab")
		)
		(fp_line
			(start -0.67945 0.3048)
			(end -0.67945 -0.305054)
			(stroke
				(width 0.1)
				(type default)
			)
			(layer "F.Fab")
		)
		(fp_line
			(start -0.67945 -0.305054)
			(end -0.12065 -0.305054)
			(stroke
				(width 0.1)
				(type default)
			)
			(layer "F.Fab")
		)
		(pad "1" smd circle
			(at -0.40005 0 180)
			(size 0 0)
			(layers "F.Cu" "F.Mask" "F.Paste")
			(net "P12V_AUX")
		)
		(pad "2" smd circle
			(at 0.40005 0 180)
			(size 0 0)
			(layers "F.Cu" "F.Mask" "F.Paste")
			(net "PVDDCR_CPU0_P0_VINSEN")
		)
	)
	(footprint ""
		(layer "F.Cu")
		(at 75.05573 -386.951474)
		(property "Reference" "R598"
			(at 0 0 0)
			(layer "F.SilkS")
			(hide yes)
			(effects
				(font
					(size 1.27 1.27)
				)
			)
		)
		(property "Value" ""
			(at 0 0 0)
			(layer "F.Fab")
			(effects
				(font
					(size 1.27 1.27)
				)
			)
		)
		(duplicate_pad_numbers_are_jumpers no)
		(fp_line
			(start -0.32512 -0.175006)
			(end 0.32512 -0.175006)
			(stroke
				(width 0.1)
				(type default)
			)
			(layer "F.Fab")
		)
		(fp_line
			(start -0.32512 0.175006)
			(end -0.32512 -0.175006)
			(stroke
				(width 0.1)
				(type default)
			)
			(layer "F.Fab")
		)
		(fp_line
			(start 0.32512 -0.175006)
			(end 0.32512 0.175006)
			(stroke
				(width 0.1)
				(type default)
			)
			(layer "F.Fab")
		)
		(fp_line
			(start 0.32512 0.175006)
			(end -0.32512 0.175006)
			(stroke
				(width 0.1)
				(type default)
			)
			(layer "F.Fab")
		)
		(pad "1" smd rect
			(at -0.2667 0)
			(size 0.3048 0.381)
			(layers "F.Cu" "F.Mask" "F.Paste")
			(net "CLK_100M_RETIMER_CPU1_P1_R_DN")
		)
		(pad "2" smd rect
			(at 0.2667 0 180)
			(size 0.3048 0.381)
			(layers "F.Cu" "F.Mask" "F.Paste")
			(net "CLK_100M_RETIMER_CPU1_P1_DN")
		)
	)
	(footprint ""
		(layer "F.Cu")
		(at 30.484064 -75.234038 90)
		(property "Reference" "R1318"
			(at 0 0 90)
			(layer "F.SilkS")
			(hide yes)
			(effects
				(font
					(size 1.27 1.27)
				)
			)
		)
		(property "Value" ""
			(at 0 0 90)
			(layer "F.Fab")
			(effects
				(font
					(size 1.27 1.27)
				)
			)
		)
		(duplicate_pad_numbers_are_jumpers no)
		(fp_line
			(start 0.7874 -0.4064)
			(end 0.7874 0.4064)
			(stroke
				(width 0.1524)
				(type default)
			)
			(layer "F.SilkS")
		)
		(fp_line
			(start -0.7874 -0.4064)
			(end 0.7874 -0.4064)
			(stroke
				(width 0.1524)
				(type default)
			)
			(layer "F.SilkS")
		)
		(fp_line
			(start 0.7874 0.4064)
			(end -0.7874 0.4064)
			(stroke
				(width 0.1524)
				(type default)
			)
			(layer "F.SilkS")
		)
		(fp_line
			(start -0.7874 0.4064)
			(end -0.7874 -0.4064)
			(stroke
				(width 0.1524)
				(type default)
			)
			(layer "F.SilkS")
		)
		(fp_line
			(start -0.12065 -0.305054)
			(end -0.12065 -0.2794)
			(stroke
				(width 0.1)
				(type default)
			)
			(layer "F.Fab")
		)
		(fp_line
			(start -0.67945 -0.305054)
			(end -0.12065 -0.305054)
			(stroke
				(width 0.1)
				(type default)
			)
			(layer "F.Fab")
		)
		(fp_line
			(start 0.67945 -0.3048)
			(end 0.67945 0.3048)
			(stroke
				(width 0.1)
				(type default)
			)
			(layer "F.Fab")
		)
		(fp_line
			(start 0.12065 -0.3048)
			(end 0.67945 -0.3048)
			(stroke
				(width 0.1)
				(type default)
			)
			(layer "F.Fab")
		)
		(fp_line
			(start 0.12065 -0.2794)
			(end 0.12065 -0.3048)
			(stroke
				(width 0.1)
				(type default)
			)
			(layer "F.Fab")
		)
		(fp_line
			(start -0.12065 -0.2794)
			(end 0.12065 -0.2794)
			(stroke
				(width 0.1)
				(type default)
			)
			(layer "F.Fab")
		)
		(fp_line
			(start 0.120396 0.2794)
			(end -0.12065 0.2794)
			(stroke
				(width 0.1)
				(type default)
			)
			(layer "F.Fab")
		)
		(fp_line
			(start -0.12065 0.2794)
			(end -0.12065 0.3048)
			(stroke
				(width 0.1)
				(type default)
			)
			(layer "F.Fab")
		)
		(fp_line
			(start 0.67945 0.3048)
			(end 0.120396 0.3048)
			(stroke
				(width 0.1)
				(type default)
			)
			(layer "F.Fab")
		)
		(fp_line
			(start 0.120396 0.3048)
			(end 0.120396 0.2794)
			(stroke
				(width 0.1)
				(type default)
			)
			(layer "F.Fab")
		)
		(fp_line
			(start -0.12065 0.3048)
			(end -0.67945 0.3048)
			(stroke
				(width 0.1)
				(type default)
			)
			(layer "F.Fab")
		)
		(fp_line
			(start -0.67945 0.3048)
			(end -0.67945 -0.305054)
			(stroke
				(width 0.1)
				(type default)
			)
			(layer "F.Fab")
		)
		(pad "1" smd circle
			(at -0.40005 0 90)
			(size 0 0)
			(layers "F.Cu" "F.Mask" "F.Paste")
			(net "PD_U212_EN_N")
		)
		(pad "2" smd circle
			(at 0.40005 0 90)
			(size 0 0)
			(layers "F.Cu" "F.Mask" "F.Paste")
			(net "GND")
		)
	)
)
